# S9S_MB_2U (Grand Teton) — schematic netlist excerpt (pin names and nets, part order shuffled) for the footprints in the layout excerpt that follows; sources: Cadence DE-HDL packaged netlist, KiCad conversion of 03242023_DA0F0TMBIJ0_F0T_Motherboard_J_brd_V01_OCP.brd

R502  Q_RES  20K 1% CHIP  pkg 0402LF  page 198 : A = P3V3_AUX ; B = FM_PCH_CONSENT_STRAP_N
R137  Q_RES  100 1% CHIP  pkg 0402LF  page 125 : A = PWRGD_DRAMPWRGD_CPU1_CD_LVC1_R2 ; B = PVCCD_HV_CPU1
C505  Q_CAP  47UF 4V 20% X6S  pkg C0805  page 75 : A = PVCCFA_EHV_FIVRA_CPU0 ; B = GND

(kicad_pcb
	(version 20260206)
	(generator "pcbnew")
	(generator_version "10.0")
	(general
		(thickness 1.6)
		(legacy_teardrops no)
	)
	(paper "A4")
	(title_block
		(title "03242023_DA0F0TMBIJ0_F0T_Motherboard_J_brd_V01_OCP.brd")
		(comment 1 "Grand Teton / footprints 5833-5835 of 6105")
	)
	(layers
		(0 "F.Cu" signal "TOP")
		(4 "In1.Cu" signal "GND")
		(6 "In2.Cu" signal "IN1")
		(8 "In3.Cu" signal "GND1")
		(10 "In4.Cu" signal "IN2")
		(12 "In5.Cu" signal "GND2")
		(14 "In6.Cu" signal "IN3")
		(16 "In7.Cu" signal "GND3")
		(18 "In8.Cu" signal "VCC")
		(20 "In9.Cu" signal "VCC1")
		(22 "In10.Cu" signal "GND4")
		(24 "In11.Cu" signal "IN4")
		(26 "In12.Cu" signal "GND5")
		(28 "In13.Cu" signal "IN5")
		(30 "In14.Cu" signal "GND6")
		(32 "In15.Cu" signal "IN6")
		(34 "In16.Cu" signal "GND7")
		(2 "B.Cu" signal "BOTTOM")
		(9 "F.Adhes" user "F.Adhesive")
		(11 "B.Adhes" user "B.Adhesive")
		(13 "F.Paste" user "Package Geometry/Pastemask Top")
		(15 "B.Paste" user "Package Geometry/Pastemask Bottom")
		(5 "F.SilkS" user "Ref Des/Silkscreen Top")
		(7 "B.SilkS" user "Ref Des/Silkscreen Bottom")
		(1 "F.Mask" user "Board Geometry/Soldermask Top")
		(3 "B.Mask" user "Board Geometry/Soldermask Bottom")
		(17 "Dwgs.User" user "User.Drawings")
		(19 "Cmts.User" user "User.Comments")
		(21 "Eco1.User" user "User.Eco1")
		(23 "Eco2.User" user "User.Eco2")
		(25 "Edge.Cuts" user "Board Geometry/Outline")
		(27 "Margin" user)
		(31 "F.CrtYd" user "Package Geometry/Place Bound Top")
		(29 "B.CrtYd" user "Package Geometry/Place Bound Bottom")
		(35 "F.Fab" user "Ref Des/Assembly Top")
		(33 "B.Fab" user "Ref Des/Assembly Bottom")
	)
	(footprint ""
		(layer "B.Cu")
		(at 344.820748 -31.527242)
		(property "Reference" "R502"
			(at 0 0 0)
			(layer "B.SilkS")
			(hide yes)
			(effects
				(font
					(size 1.27 1.27)
				)
				(justify mirror)
			)
		)
		(property "Value" ""
			(at 0 0 0)
			(layer "B.Fab")
			(effects
				(font
					(size 1.27 1.27)
				)
				(justify mirror)
			)
		)
		(duplicate_pad_numbers_are_jumpers no)
		(fp_line
			(start -0.7874 -0.4064)
			(end -0.7874 0.4064)
			(stroke
				(width 0.1524)
				(type default)
			)
			(layer "B.SilkS")
		)
		(fp_line
			(start -0.7874 0.4064)
			(end 0.7874 0.4064)
			(stroke
				(width 0.1524)
				(type default)
			)
			(layer "B.SilkS")
		)
		(fp_line
			(start 0.7874 -0.4064)
			(end -0.7874 -0.4064)
			(stroke
				(width 0.1524)
				(type default)
			)
			(layer "B.SilkS")
		)
		(fp_line
			(start 0.7874 0.4064)
			(end 0.7874 -0.4064)
			(stroke
				(width 0.1524)
				(type default)
			)
			(layer "B.SilkS")
		)
		(fp_line
			(start -0.67945 -0.3048)
			(end -0.67945 0.3048)
			(stroke
				(width 0.1)
				(type default)
			)
			(layer "B.Fab")
		)
		(fp_line
			(start -0.67945 0.3048)
			(end -0.120396 0.3048)
			(stroke
				(width 0.1)
				(type default)
			)
			(layer "B.Fab")
		)
		(fp_line
			(start -0.12065 -0.3048)
			(end -0.67945 -0.3048)
			(stroke
				(width 0.1)
				(type default)
			)
			(layer "B.Fab")
		)
		(fp_line
			(start -0.12065 -0.2794)
			(end -0.12065 -0.3048)
			(stroke
				(width 0.1)
				(type default)
			)
			(layer "B.Fab")
		)
		(fp_line
			(start -0.120396 0.2794)
			(end 0.12065 0.2794)
			(stroke
				(width 0.1)
				(type default)
			)
			(layer "B.Fab")
		)
		(fp_line
			(start -0.120396 0.3048)
			(end -0.120396 0.2794)
			(stroke
				(width 0.1)
				(type default)
			)
			(layer "B.Fab")
		)
		(fp_line
			(start 0.12065 -0.305054)
			(end 0.12065 -0.2794)
			(stroke
				(width 0.1)
				(type default)
			)
			(layer "B.Fab")
		)
		(fp_line
			(start 0.12065 -0.2794)
			(end -0.12065 -0.2794)
			(stroke
				(width 0.1)
				(type default)
			)
			(layer "B.Fab")
		)
		(fp_line
			(start 0.12065 0.2794)
			(end 0.12065 0.3048)
			(stroke
				(width 0.1)
				(type default)
			)
			(layer "B.Fab")
		)
		(fp_line
			(start 0.12065 0.3048)
			(end 0.67945 0.3048)
			(stroke
				(width 0.1)
				(type default)
			)
			(layer "B.Fab")
		)
		(fp_line
			(start 0.67945 -0.305054)
			(end 0.12065 -0.305054)
			(stroke
				(width 0.1)
				(type default)
			)
			(layer "B.Fab")
		)
		(fp_line
			(start 0.67945 0.3048)
			(end 0.67945 -0.305054)
			(stroke
				(width 0.1)
				(type default)
			)
			(layer "B.Fab")
		)
		(pad "1" smd circle
			(at 0.40005 0 180)
			(size 0 0)
			(layers "B.Cu" "B.Mask" "B.Paste")
			(net "P3V3_AUX")
		)
		(pad "2" smd circle
			(at -0.40005 0 180)
			(size 0 0)
			(layers "B.Cu" "B.Mask" "B.Paste")
			(net "FM_PCH_CONSENT_STRAP_N")
		)
	)
	(footprint ""
		(layer "B.Cu")
		(at 355.397308 -259.531866 90)
		(property "Reference" "C505"
			(at 0 0 90)
			(layer "B.SilkS")
			(hide yes)
			(effects
				(font
					(size 1.27 1.27)
				)
				(justify mirror)
			)
		)
		(property "Value" ""
			(at 0 0 90)
			(layer "B.Fab")
			(effects
				(font
					(size 1.27 1.27)
				)
				(justify mirror)
			)
		)
		(duplicate_pad_numbers_are_jumpers no)
		(fp_line
			(start 1.524 -0.762)
			(end -1.524 -0.762)
			(stroke
				(width 0.1524)
				(type default)
			)
			(layer "B.SilkS")
		)
		(fp_line
			(start -1.524 -0.762)
			(end -1.524 0.762)
			(stroke
				(width 0.1524)
				(type default)
			)
			(layer "B.SilkS")
		)
		(fp_line
			(start 1.524 0.762)
			(end 1.524 -0.762)
			(stroke
				(width 0.1524)
				(type default)
			)
			(layer "B.SilkS")
		)
		(fp_line
			(start -1.524 0.762)
			(end 1.524 0.762)
			(stroke
				(width 0.1524)
				(type default)
			)
			(layer "B.SilkS")
		)
		(fp_line
			(start 1.1049 -0.724916)
			(end 1.1049 0.724916)
			(stroke
				(width 0.1)
				(type default)
			)
			(layer "B.Fab")
		)
		(fp_line
			(start -1.1049 -0.724916)
			(end 1.1049 -0.724916)
			(stroke
				(width 0.1)
				(type default)
			)
			(layer "B.Fab")
		)
		(fp_line
			(start 1.1049 0.724916)
			(end -1.1049 0.724916)
			(stroke
				(width 0.1)
				(type default)
			)
			(layer "B.Fab")
		)
		(fp_line
			(start -1.1049 0.724916)
			(end -1.1049 -0.724916)
			(stroke
				(width 0.1)
				(type default)
			)
			(layer "B.Fab")
		)
		(pad "1" smd rect
			(at 0.889 0 90)
			(size 1.016 1.27)
			(layers "B.Cu" "B.Mask" "B.Paste")
			(net "PVCCFA_EHV_FIVRA_CPU0")
		)
		(pad "2" smd rect
			(at -0.889 0 90)
			(size 1.016 1.27)
			(layers "B.Cu" "B.Mask" "B.Paste")
			(net "GND")
		)
	)
	(footprint ""
		(layer "B.Cu")
		(at 64.637158 -192.96253 90)
		(property "Reference" "R137"
			(at 0 0 90)
			(layer "B.SilkS")
			(hide yes)
			(effects
				(font
					(size 1.27 1.27)
				)
				(justify mirror)
			)
		)
		(property "Value" ""
			(at 0 0 90)
			(layer "B.Fab")
			(effects
				(font
					(size 1.27 1.27)
				)
				(justify mirror)
			)
		)
		(duplicate_pad_numbers_are_jumpers no)
		(fp_line
			(start 0.7874 -0.4064)
			(end -0.7874 -0.4064)
			(stroke
				(width 0.1524)
				(type default)
			)
			(layer "B.SilkS")
		)
		(fp_line
			(start -0.7874 -0.4064)
			(end -0.7874 0.4064)
			(stroke
				(width 0.1524)
				(type default)
			)
			(layer "B.SilkS")
		)
		(fp_line
			(start 0.7874 0.4064)
			(end 0.7874 -0.4064)
			(stroke
				(width 0.1524)
				(type default)
			)
			(layer "B.SilkS")
		)
		(fp_line
			(start -0.7874 0.4064)
			(end 0.7874 0.4064)
			(stroke
				(width 0.1524)
				(type default)
			)
			(layer "B.SilkS")
		)
		(fp_line
			(start 0.67945 -0.305054)
			(end 0.12065 -0.305054)
			(stroke
				(width 0.1)
				(type default)
			)
			(layer "B.Fab")
		)
		(fp_line
			(start 0.12065 -0.305054)
			(end 0.12065 -0.2794)
			(stroke
				(width 0.1)
				(type default)
			)
			(layer "B.Fab")
		)
		(fp_line
			(start -0.12065 -0.3048)
			(end -0.67945 -0.3048)
			(stroke
				(width 0.1)
				(type default)
			)
			(layer "B.Fab")
		)
		(fp_line
			(start -0.67945 -0.3048)
			(end -0.67945 0.3048)
			(stroke
				(width 0.1)
				(type default)
			)
			(layer "B.Fab")
		)
		(fp_line
			(start 0.12065 -0.2794)
			(end -0.12065 -0.2794)
			(stroke
				(width 0.1)
				(type default)
			)
			(layer "B.Fab")
		)
		(fp_line
			(start -0.12065 -0.2794)
			(end -0.12065 -0.3048)
			(stroke
				(width 0.1)
				(type default)
			)
			(layer "B.Fab")
		)
		(fp_line
			(start 0.12065 0.2794)
			(end 0.12065 0.3048)
			(stroke
				(width 0.1)
				(type default)
			)
			(layer "B.Fab")
		)
		(fp_line
			(start -0.120396 0.2794)
			(end 0.12065 0.2794)
			(stroke
				(width 0.1)
				(type default)
			)
			(layer "B.Fab")
		)
		(fp_line
			(start 0.67945 0.3048)
			(end 0.67945 -0.305054)
			(stroke
				(width 0.1)
				(type default)
			)
			(layer "B.Fab")
		)
		(fp_line
			(start 0.12065 0.3048)
			(end 0.67945 0.3048)
			(stroke
				(width 0.1)
				(type default)
			)
			(layer "B.Fab")
		)
		(fp_line
			(start -0.120396 0.3048)
			(end -0.120396 0.2794)
			(stroke
				(width 0.1)
				(type default)
			)
			(layer "B.Fab")
		)
		(fp_line
			(start -0.67945 0.3048)
			(end -0.120396 0.3048)
			(stroke
				(width 0.1)
				(type default)
			)
			(layer "B.Fab")
		)
		(pad "1" smd circle
			(at 0.40005 0 270)
			(size 0 0)
			(layers "B.Cu" "B.Mask" "B.Paste")
			(net "PWRGD_DRAMPWRGD_CPU1_CD_LVC1_R2")
		)
		(pad "2" smd circle
			(at -0.40005 0 270)
			(size 0 0)
			(layers "B.Cu" "B.Mask" "B.Paste")
			(net "PVCCD_HV_CPU1")
		)
	)
)
